(kicad_pcb
	(version 20241229)
	(generator "pcbnew")
	(generator_version "9.0")
	(general
		(thickness 1.599998)
		(legacy_teardrops no)
	)
	(paper "A4")
	(title_block
		(title "Artix - Datacenter Secure Control Module (DC-SCM)")
		(date "2024-11-06")
		(rev "1.1.3")
		(comment 9 "footprints 458-462 of 544")
	)
	(layers
		(0 "F.Cu" signal)
		(4 "In1.Cu" signal)
		(6 "In2.Cu" signal)
		(8 "In3.Cu" signal)
		(10 "In4.Cu" signal)
		(12 "In5.Cu" signal)
		(14 "In6.Cu" signal)
		(2 "B.Cu" signal)
		(9 "F.Adhes" user "F.Adhesive")
		(11 "B.Adhes" user "B.Adhesive")
		(13 "F.Paste" user)
		(15 "B.Paste" user)
		(5 "F.SilkS" user "F.Silkscreen")
		(7 "B.SilkS" user "B.Silkscreen")
		(1 "F.Mask" user)
		(3 "B.Mask" user)
		(17 "Dwgs.User" user "User.Drawings")
		(19 "Cmts.User" user "User.Comments")
		(21 "Eco1.User" user "User.Eco1")
		(23 "Eco2.User" user "User.Eco2")
		(25 "Edge.Cuts" user)
		(27 "Margin" user)
		(31 "F.CrtYd" user "F.Courtyard")
		(29 "B.CrtYd" user "B.Courtyard")
		(35 "F.Fab" user)
		(33 "B.Fab" user)
	)
	(footprint "antmicro-footprints:SOT-23-3"
		(layer "B.Cu")
		(at 71.04 84.49 90)
		(property "Reference" "Q12"
			(at 0.99 -2.74 180)
			(layer "B.SilkS")
			(effects
				(font
					(size 0.7 0.7)
					(thickness 0.15)
				)
				(justify right bottom mirror)
			)
		)
		(property "Value" "2N7002_SOT-23-3"
			(at -1.9 -2.7 90)
			(layer "B.Fab")
			(effects
				(font
					(size 0.7 0.7)
					(thickness 0.15)
				)
				(justify right bottom mirror)
			)
		)
		(property "Datasheet" "https://www.onsemi.com/pub/Collateral/NDS7002A-D.PDF"
			(at 0 0 90)
			(layer "F.Fab")
			(hide yes)
			(effects
				(font
					(size 1.27 1.27)
					(thickness 0.15)
				)
			)
		)
		(property "Description" "Power MOSFET, N Channel, 60 V, 115 mA, 1.2 ohm, SOT-23, Surface Mount"
			(at 0 0 90)
			(layer "F.Fab")
			(hide yes)
			(effects
				(font
					(size 1.27 1.27)
					(thickness 0.15)
				)
			)
		)
		(property "Author" "Antmicro"
			(at 155.53 13.45 0)
			(layer "B.Fab")
			(hide yes)
			(effects
				(font
					(size 1 1)
					(thickness 0.15)
				)
				(justify mirror)
			)
		)
		(property "License" "Apache-2.0"
			(at 155.53 13.45 0)
			(layer "B.Fab")
			(hide yes)
			(effects
				(font
					(size 1 1)
					(thickness 0.15)
				)
				(justify mirror)
			)
		)
		(property "MPN" "2N7002"
			(at 155.53 13.45 0)
			(layer "B.Fab")
			(hide yes)
			(effects
				(font
					(size 1 1)
					(thickness 0.15)
				)
				(justify mirror)
			)
		)
		(property "Manufacturer" "ON Semiconductor"
			(at 155.53 13.45 0)
			(layer "B.Fab")
			(hide yes)
			(effects
				(font
					(size 1 1)
					(thickness 0.15)
				)
				(justify mirror)
			)
		)
		(sheetname "/FPGA banks 34-35 & CFG/")
		(sheetfile "fpga-banks-34-25-cfg.kicad_sch")
		(attr smd)
		(fp_line
			(start 0.7 -1.5)
			(end -0.7 -1.5)
			(stroke
				(width 0.15)
				(type solid)
			)
			(layer "B.SilkS")
		)
		(fp_line
			(start -0.7 -1.5)
			(end -0.7 -1.35)
			(stroke
				(width 0.15)
				(type solid)
			)
			(layer "B.SilkS")
		)
		(fp_line
			(start 0.7 -0.4)
			(end 0.7 -1.5)
			(stroke
				(width 0.15)
				(type solid)
			)
			(layer "B.SilkS")
		)
		(fp_line
			(start 0.7 0.4)
			(end 0.7 1.5)
			(stroke
				(width 0.15)
				(type solid)
			)
			(layer "B.SilkS")
		)
		(fp_line
			(start -0.85 1.35)
			(end -0.7 1.5)
			(stroke
				(width 0.15)
				(type solid)
			)
			(layer "B.SilkS")
		)
		(fp_line
			(start -1.45 1.35)
			(end -0.85 1.35)
			(stroke
				(width 0.15)
				(type solid)
			)
			(layer "B.SilkS")
		)
		(fp_line
			(start 0.7 1.5)
			(end -0.7 1.5)
			(stroke
				(width 0.15)
				(type solid)
			)
			(layer "B.SilkS")
		)
		(fp_line
			(start 0.85 -1.65)
			(end -0.85 -1.65)
			(stroke
				(width 0.05)
				(type solid)
			)
			(layer "B.CrtYd")
		)
		(fp_line
			(start -0.85 -1.65)
			(end -0.85 -1.4)
			(stroke
				(width 0.05)
				(type solid)
			)
			(layer "B.CrtYd")
		)
		(fp_line
			(start -0.85 -1.4)
			(end -1.75 -1.4)
			(stroke
				(width 0.05)
				(type solid)
			)
			(layer "B.CrtYd")
		)
		(fp_line
			(start -1.75 -1.4)
			(end -1.75 -0.5)
			(stroke
				(width 0.05)
				(type solid)
			)
			(layer "B.CrtYd")
		)
		(fp_line
			(start -0.85 -0.5)
			(end -0.85 0.5)
			(stroke
				(width 0.05)
				(type solid)
			)
			(layer "B.CrtYd")
		)
		(fp_line
			(start -1.75 -0.5)
			(end -0.85 -0.5)
			(stroke
				(width 0.05)
				(type solid)
			)
			(layer "B.CrtYd")
		)
		(fp_line
			(start 1.75 -0.45)
			(end 0.85 -0.45)
			(stroke
				(width 0.05)
				(type solid)
			)
			(layer "B.CrtYd")
		)
		(fp_line
			(start 0.85 -0.45)
			(end 0.85 -1.65)
			(stroke
				(width 0.05)
				(type solid)
			)
			(layer "B.CrtYd")
		)
		(fp_line
			(start 1.75 0.45)
			(end 1.75 -0.45)
			(stroke
				(width 0.05)
				(type solid)
			)
			(layer "B.CrtYd")
		)
		(fp_line
			(start 0.825 0.45)
			(end 1.75 0.45)
			(stroke
				(width 0.05)
				(type solid)
			)
			(layer "B.CrtYd")
		)
		(fp_line
			(start -0.85 0.5)
			(end -1.75 0.5)
			(stroke
				(width 0.05)
				(type solid)
			)
			(layer "B.CrtYd")
		)
		(fp_line
			(start -1.75 0.5)
			(end -1.75 1.4)
			(stroke
				(width 0.05)
				(type solid)
			)
			(layer "B.CrtYd")
		)
		(fp_line
			(start -0.9 1.4)
			(end -1.75 1.4)
			(stroke
				(width 0.05)
				(type solid)
			)
			(layer "B.CrtYd")
		)
		(fp_line
			(start 0.825 1.6)
			(end 0.825 0.45)
			(stroke
				(width 0.05)
				(type solid)
			)
			(layer "B.CrtYd")
		)
		(fp_line
			(start -0.9 1.6)
			(end -0.9 1.4)
			(stroke
				(width 0.05)
				(type solid)
			)
			(layer "B.CrtYd")
		)
		(fp_line
			(start -0.9 1.6)
			(end 0.825 1.6)
			(stroke
				(width 0.05)
				(type solid)
			)
			(layer "B.CrtYd")
		)
		(fp_line
			(start 0.688 -1.519)
			(end 0.688 1.52)
			(stroke
				(width 0.15)
				(type solid)
			)
			(layer "B.Fab")
		)
		(fp_line
			(start -0.712 -1.519)
			(end 0.688 -1.519)
			(stroke
				(width 0.15)
				(type solid)
			)
			(layer "B.Fab")
		)
		(fp_line
			(start -0.712 1.325)
			(end -0.712 -1.523)
			(stroke
				(width 0.15)
				(type solid)
			)
			(layer "B.Fab")
		)
		(fp_line
			(start -0.437 1.526)
			(end -0.712 1.325)
			(stroke
				(width 0.15)
				(type solid)
			)
			(layer "B.Fab")
		)
		(fp_line
			(start -0.437 1.526)
			(end 0.688 1.526)
			(stroke
				(width 0.15)
				(type solid)
			)
			(layer "B.Fab")
		)
		(pad "1" smd roundrect
			(at -1.1 0.951 90)
			(size 1 0.6)
			(layers "B.Cu" "B.Mask" "B.Paste")
			(roundrect_rratio 0.15)
			(net 222 "INIT")
			(pinfunction "G")
			(pintype "input")
		)
		(pad "2" smd roundrect
			(at -1.1 -0.949 90)
			(size 1 0.6)
			(layers "B.Cu" "B.Mask" "B.Paste")
			(roundrect_rratio 0.15)
			(net 1 "GND")
			(pinfunction "S")
			(pintype "passive")
		)
		(pad "3" smd roundrect
			(at 1.1 0.0005 90)
			(size 1 0.6)
			(layers "B.Cu" "B.Mask" "B.Paste")
			(roundrect_rratio 0.15)
			(net 225 "Net-(D9-C)")
			(pinfunction "D")
			(pintype "passive")
		)
	)
	(footprint "antmicro-footprints:C_0402_1005Metric"
		(layer "B.Cu")
		(at 99.775 114.675 180)
		(descr "Capacitor SMD 0402")
		(tags "capacitor SMD 0402")
		(property "Reference" "C129"
			(at -1.251 0.45 0)
			(layer "B.SilkS")
			(effects
				(font
					(size 0.7 0.7)
					(thickness 0.15)
				)
				(justify left bottom mirror)
			)
		)
		(property "Value" "C_470n_0402"
			(at 0 -1.4 0)
			(layer "B.Fab")
			(effects
				(font
					(size 0.7 0.7)
					(thickness 0.15)
				)
				(justify left bottom mirror)
			)
		)
		(property "Datasheet" "https://product.tdk.com/en/search/capacitor/ceramic/mlcc/info?part_no=C1005X5R1E474M050BB"
			(at 0 0 180)
			(layer "F.Fab")
			(hide yes)
			(effects
				(font
					(size 1.27 1.27)
					(thickness 0.15)
				)
			)
		)
		(property "Description" "SMD Multilayer Ceramic Capacitor, 0.47 µF, 25 V, 0402 [1005 Metric], ± 20%, X5R, C"
			(at 0 0 180)
			(layer "F.Fab")
			(hide yes)
			(effects
				(font
					(size 1.27 1.27)
					(thickness 0.15)
				)
			)
		)
		(property "Author" "Antmicro"
			(at 199.55 229.35 0)
			(layer "B.Fab")
			(hide yes)
			(effects
				(font
					(size 1 1)
					(thickness 0.15)
				)
				(justify mirror)
			)
		)
		(property "Dielectric" ""
			(at 199.55 229.35 0)
			(layer "B.Fab")
			(hide yes)
			(effects
				(font
					(size 1 1)
					(thickness 0.15)
				)
				(justify mirror)
			)
		)
		(property "License" "Apache-2.0"
			(at 199.55 229.35 0)
			(layer "B.Fab")
			(hide yes)
			(effects
				(font
					(size 1 1)
					(thickness 0.15)
				)
				(justify mirror)
			)
		)
		(property "MPN" "C1005X5R1E474M050BB"
			(at 199.55 229.35 0)
			(layer "B.Fab")
			(hide yes)
			(effects
				(font
					(size 1 1)
					(thickness 0.15)
				)
				(justify mirror)
			)
		)
		(property "Manufacturer" "TDK"
			(at 199.55 229.35 0)
			(layer "B.Fab")
			(hide yes)
			(effects
				(font
					(size 1 1)
					(thickness 0.15)
				)
				(justify mirror)
			)
		)
		(property "Val" "470n"
			(at 199.55 229.35 0)
			(layer "B.Fab")
			(hide yes)
			(effects
				(font
					(size 1 1)
					(thickness 0.15)
				)
				(justify mirror)
			)
		)
		(property "Voltage" ""
			(at 199.55 229.35 0)
			(layer "B.Fab")
			(hide yes)
			(effects
				(font
					(size 1 1)
					(thickness 0.15)
				)
				(justify mirror)
			)
		)
		(sheetname "/FPGA banks 13-16/")
		(sheetfile "fpga-banks-13-16.kicad_sch")
		(attr smd)
		(fp_rect
			(start -0.925 0.47)
			(end 0.925 -0.47)
			(stroke
				(width 0.05)
				(type default)
			)
			(fill no)
			(layer "B.CrtYd")
		)
		(fp_line
			(start 0.504 0.25)
			(end 0.504 -0.248)
			(stroke
				(width 0.15)
				(type solid)
			)
			(layer "B.Fab")
		)
		(fp_line
			(start 0.504 -0.248)
			(end -0.494 -0.248)
			(stroke
				(width 0.15)
				(type solid)
			)
			(layer "B.Fab")
		)
		(fp_line
			(start -0.494 0.25)
			(end 0.504 0.25)
			(stroke
				(width 0.15)
				(type solid)
			)
			(layer "B.Fab")
		)
		(fp_line
			(start -0.494 -0.248)
			(end -0.494 0.25)
			(stroke
				(width 0.15)
				(type solid)
			)
			(layer "B.Fab")
		)
		(pad "1" smd roundrect
			(at -0.48 0 180)
			(size 0.59 0.64)
			(layers "B.Cu" "B.Mask" "B.Paste")
			(roundrect_rratio 0.25)
			(net 1 "GND")
			(pintype "passive")
		)
		(pad "2" smd roundrect
			(at 0.48 0 180)
			(size 0.59 0.64)
			(layers "B.Cu" "B.Mask" "B.Paste")
			(roundrect_rratio 0.25)
			(net 2 "VCC3V3")
			(pintype "passive")
		)
	)
	(footprint "antmicro-footprints:R_0402_1005Metric"
		(layer "B.Cu")
		(at 94.075 122.675 180)
		(descr "Resistor SMD 0402")
		(tags "resistor SMD 0402")
		(property "Reference" "R143"
			(at -1.325 0.475 0)
			(layer "B.SilkS")
			(effects
				(font
					(size 0.7 0.7)
					(thickness 0.15)
				)
				(justify left bottom mirror)
			)
		)
		(property "Value" "R_100R_0402"
			(at 0 -1.4 0)
			(layer "B.Fab")
			(effects
				(font
					(size 0.7 0.7)
					(thickness 0.15)
				)
				(justify left bottom mirror)
			)
		)
		(property "Datasheet" "https://www.bourns.com/docs/product-datasheets/cr.pdf"
			(at 0 0 180)
			(layer "F.Fab")
			(hide yes)
			(effects
				(font
					(size 1.27 1.27)
					(thickness 0.15)
				)
			)
		)
		(property "Description" "SMD Chip Resistor, 100 ohm, ± 1%, 62.5 mW, 0402 [1005 Metric], Thick Film, General Purpose"
			(at 0 0 180)
			(layer "F.Fab")
			(hide yes)
			(effects
				(font
					(size 1.27 1.27)
					(thickness 0.15)
				)
			)
		)
		(property "Author" "Antmicro"
			(at 188.15 245.35 0)
			(layer "B.Fab")
			(hide yes)
			(effects
				(font
					(size 1 1)
					(thickness 0.15)
				)
				(justify mirror)
			)
		)
		(property "License" "Apache-2.0"
			(at 188.15 245.35 0)
			(layer "B.Fab")
			(hide yes)
			(effects
				(font
					(size 1 1)
					(thickness 0.15)
				)
				(justify mirror)
			)
		)
		(property "MPN" "CR0402-FX-1000GLF"
			(at 188.15 245.35 0)
			(layer "B.Fab")
			(hide yes)
			(effects
				(font
					(size 1 1)
					(thickness 0.15)
				)
				(justify mirror)
			)
		)
		(property "Manufacturer" "Bourns"
			(at 188.15 245.35 0)
			(layer "B.Fab")
			(hide yes)
			(effects
				(font
					(size 1 1)
					(thickness 0.15)
				)
				(justify mirror)
			)
		)
		(property "Tolerance" "1%"
			(at 188.15 245.35 0)
			(layer "B.Fab")
			(hide yes)
			(effects
				(font
					(size 1 1)
					(thickness 0.15)
				)
				(justify mirror)
			)
		)
		(property "Val" "100R"
			(at 188.15 245.35 0)
			(layer "B.Fab")
			(hide yes)
			(effects
				(font
					(size 1 1)
					(thickness 0.15)
				)
				(justify mirror)
			)
		)
		(sheetname "/Interfaces/")
		(sheetfile "interfaces.kicad_sch")
		(attr smd)
		(fp_rect
			(start -0.925 0.47)
			(end 0.925 -0.47)
			(stroke
				(width 0.05)
				(type default)
			)
			(fill no)
			(layer "B.CrtYd")
		)
		(fp_rect
			(start -0.5 0.25)
			(end 0.5 -0.25)
			(stroke
				(width 0.15)
				(type solid)
			)
			(fill no)
			(layer "B.Fab")
		)
		(pad "1" smd roundrect
			(at -0.48 0 180)
			(size 0.59 0.64)
			(layers "B.Cu" "B.Mask" "B.Paste")
			(roundrect_rratio 0.25)
			(net 533 "Net-(U14E-MGTRREF_216)")
			(pintype "passive")
		)
		(pad "2" smd roundrect
			(at 0.48 0 180)
			(size 0.59 0.64)
			(layers "B.Cu" "B.Mask" "B.Paste")
			(roundrect_rratio 0.25)
			(net 339 "VCC1V2")
			(pintype "passive")
		)
	)
	(footprint "antmicro-footprints:C_0402_1005Metric"
		(layer "B.Cu")
		(at 106.975 118.175 -90)
		(descr "Capacitor SMD 0402")
		(tags "capacitor SMD 0402")
		(property "Reference" "C237"
			(at -1.475 0.575 90)
			(layer "B.SilkS")
			(effects
				(font
					(size 0.7 0.7)
					(thickness 0.15)
				)
				(justify left bottom mirror)
			)
		)
		(property "Value" "C_470n_0402"
			(at 0 -1.4 90)
			(layer "B.Fab")
			(effects
				(font
					(size 0.7 0.7)
					(thickness 0.15)
				)
				(justify left bottom mirror)
			)
		)
		(property "Datasheet" "https://product.tdk.com/en/search/capacitor/ceramic/mlcc/info?part_no=C1005X5R1E474M050BB"
			(at 0 0 270)
			(layer "F.Fab")
			(hide yes)
			(effects
				(font
					(size 1.27 1.27)
					(thickness 0.15)
				)
			)
		)
		(property "Description" "SMD Multilayer Ceramic Capacitor, 0.47 µF, 25 V, 0402 [1005 Metric], ± 20%, X5R, C"
			(at 0 0 270)
			(layer "F.Fab")
			(hide yes)
			(effects
				(font
					(size 1.27 1.27)
					(thickness 0.15)
				)
			)
		)
		(property "Author" "Antmicro"
			(at -11.2 225.15 0)
			(layer "B.Fab")
			(hide yes)
			(effects
				(font
					(size 1 1)
					(thickness 0.15)
				)
				(justify mirror)
			)
		)
		(property "Dielectric" ""
			(at -11.2 225.15 0)
			(layer "B.Fab")
			(hide yes)
			(effects
				(font
					(size 1 1)
					(thickness 0.15)
				)
				(justify mirror)
			)
		)
		(property "License" "Apache-2.0"
			(at -11.2 225.15 0)
			(layer "B.Fab")
			(hide yes)
			(effects
				(font
					(size 1 1)
					(thickness 0.15)
				)
				(justify mirror)
			)
		)
		(property "MPN" "C1005X5R1E474M050BB"
			(at -11.2 225.15 0)
			(layer "B.Fab")
			(hide yes)
			(effects
				(font
					(size 1 1)
					(thickness 0.15)
				)
				(justify mirror)
			)
		)
		(property "Manufacturer" "TDK"
			(at -11.2 225.15 0)
			(layer "B.Fab")
			(hide yes)
			(effects
				(font
					(size 1 1)
					(thickness 0.15)
				)
				(justify mirror)
			)
		)
		(property "Val" "470n"
			(at -11.2 225.15 0)
			(layer "B.Fab")
			(hide yes)
			(effects
				(font
					(size 1 1)
					(thickness 0.15)
				)
				(justify mirror)
			)
		)
		(property "Voltage" ""
			(at -11.2 225.15 0)
			(layer "B.Fab")
			(hide yes)
			(effects
				(font
					(size 1 1)
					(thickness 0.15)
				)
				(justify mirror)
			)
		)
		(sheetname "/FPGA banks 34-35 & CFG/")
		(sheetfile "fpga-banks-34-25-cfg.kicad_sch")
		(attr smd)
		(fp_rect
			(start -0.925 0.47)
			(end 0.925 -0.47)
			(stroke
				(width 0.05)
				(type default)
			)
			(fill no)
			(layer "B.CrtYd")
		)
		(fp_line
			(start -0.494 0.25)
			(end 0.504 0.25)
			(stroke
				(width 0.15)
				(type solid)
			)
			(layer "B.Fab")
		)
		(fp_line
			(start 0.504 0.25)
			(end 0.504 -0.248)
			(stroke
				(width 0.15)
				(type solid)
			)
			(layer "B.Fab")
		)
		(fp_line
			(start -0.494 -0.248)
			(end -0.494 0.25)
			(stroke
				(width 0.15)
				(type solid)
			)
			(layer "B.Fab")
		)
		(fp_line
			(start 0.504 -0.248)
			(end -0.494 -0.248)
			(stroke
				(width 0.15)
				(type solid)
			)
			(layer "B.Fab")
		)
		(pad "1" smd roundrect
			(at -0.48 0 270)
			(size 0.59 0.64)
			(layers "B.Cu" "B.Mask" "B.Paste")
			(roundrect_rratio 0.25)
			(net 1 "GND")
			(pintype "passive")
		)
		(pad "2" smd roundrect
			(at 0.48 0 270)
			(size 0.59 0.64)
			(layers "B.Cu" "B.Mask" "B.Paste")
			(roundrect_rratio 0.25)
			(net 2 "VCC3V3")
			(pintype "passive")
		)
	)
	(footprint "antmicro-footprints:C_0201"
		(layer "B.Cu")
		(at 104.275 122.675)
		(descr "Capacitor SMD 0201")
		(tags "capacitor SMD 0201")
		(property "Reference" "C157"
			(at 8.325 0.425 0)
			(layer "B.SilkS")
			(effects
				(font
					(size 0.7 0.7)
					(thickness 0.15)
				)
				(justify right bottom mirror)
			)
		)
		(property "Value" "C_470n_0201"
			(at 0 -1.4 0)
			(layer "B.Fab")
			(effects
				(font
					(size 0.7 0.7)
					(thickness 0.15)
				)
				(justify right bottom mirror)
			)
		)
		(property "Datasheet" "https://product.tdk.com/en/search/capacitor/ceramic/mlcc/info?part_no=C0603X5R1A474M030BC"
			(at 0 0 0)
			(layer "F.Fab")
			(hide yes)
			(effects
				(font
					(size 1.27 1.27)
					(thickness 0.15)
				)
			)
		)
		(property "Description" "SMD Multilayer Ceramic Capacitor, 0.47 µF, 10 V, 0201 [0603 Metric], ± 20%, X5R, C"
			(at 0 0 0)
			(layer "F.Fab")
			(hide yes)
			(effects
				(font
					(size 1.27 1.27)
					(thickness 0.15)
				)
			)
		)
		(property "Author" "Antmicro"
			(at 0 0 0)
			(layer "B.Fab")
			(hide yes)
			(effects
				(font
					(size 1 1)
					(thickness 0.15)
				)
				(justify mirror)
			)
		)
		(property "Dielectric" ""
			(at 0 0 0)
			(layer "B.Fab")
			(hide yes)
			(effects
				(font
					(size 1 1)
					(thickness 0.15)
				)
				(justify mirror)
			)
		)
		(property "License" "Apache-2.0"
			(at 0 0 0)
			(layer "B.Fab")
			(hide yes)
			(effects
				(font
					(size 1 1)
					(thickness 0.15)
				)
				(justify mirror)
			)
		)
		(property "MPN" "C0603X5R1A474M030BC"
			(at 0 0 0)
			(layer "B.Fab")
			(hide yes)
			(effects
				(font
					(size 1 1)
					(thickness 0.15)
				)
				(justify mirror)
			)
		)
		(property "Manufacturer" "TDK"
			(at 0 0 0)
			(layer "B.Fab")
			(hide yes)
			(effects
				(font
					(size 1 1)
					(thickness 0.15)
				)
				(justify mirror)
			)
		)
		(property "Public" "False"
			(at 0 0 0)
			(layer "B.Fab")
			(hide yes)
			(effects
				(font
					(size 1 1)
					(thickness 0.15)
				)
				(justify mirror)
			)
		)
		(property "Val" "470n"
			(at 0 0 0)
			(layer "B.Fab")
			(hide yes)
			(effects
				(font
					(size 1 1)
					(thickness 0.15)
				)
				(justify mirror)
			)
		)
		(property "Voltage" ""
			(at 0 0 0)
			(layer "B.Fab")
			(hide yes)
			(effects
				(font
					(size 1 1)
					(thickness 0.15)
				)
				(justify mirror)
			)
		)
		(property "DNP" ""
			(at 0 0 0)
			(unlocked yes)
			(layer "B.Fab")
			(hide yes)
			(effects
				(font
					(size 1 1)
					(thickness 0.15)
				)
				(justify mirror)
			)
		)
		(sheetname "/FPGA power supply/")
		(sheetfile "fpga-power-supply.kicad_sch")
		(attr smd)
		(fp_rect
			(start -0.7 0.35)
			(end 0.7 -0.35)
			(stroke
				(width 0.05)
				(type default)
			)
			(fill no)
			(layer "B.CrtYd")
		)
		(fp_rect
			(start 0.3 -0.15)
			(end -0.301 0.149)
			(stroke
				(width 0.15)
				(type solid)
			)
			(fill no)
			(layer "B.Fab")
		)
		(pad "" smd roundrect
			(at -0.349 0.002)
			(size 0.318 0.36)
			(layers "B.Paste")
			(roundrect_rratio 0.25)
		)
		(pad "" smd roundrect
			(at 0.341 0.002)
			(size 0.318 0.36)
			(layers "B.Paste")
			(roundrect_rratio 0.25)
		)
		(pad "1" smd roundrect
			(at -0.321 0.002)
			(size 0.46 0.4)
			(layers "B.Cu" "B.Mask")
			(roundrect_rratio 0.25)
			(net 1 "GND")
			(pintype "passive")
		)
		(pad "2" smd roundrect
			(at 0.32 0.002)
			(size 0.46 0.4)
			(layers "B.Cu" "B.Mask")
			(roundrect_rratio 0.25)
			(net 6 "VCC1V0")
			(pintype "passive")
		)
	)
)
